# S9S_MB_2U (Grand Teton) — schematic netlist excerpt (pin names and nets, part order shuffled) for the footprints in the layout excerpt that follows; sources: Cadence DE-HDL packaged netlist, KiCad conversion of 03242023_DA0F0TMBIJ0_F0T_Motherboard_J_brd_V01_OCP.brd

J42  SCONN60_ASP21410801  SCONN60_ASP-214108-01 IO  pkg CON_60S2H2D4S_P0-5_LDV  page 131
  \1\  = P1V05_PCH_AUX
  \2\  = JTAG_DBP_TMS_R
  \3\  = JTAG_DBP_CPU_GTL_TCK_R
  \4\  = JTAG_DBP_TDO_R
  \5\  = JTAG_DBP_TDI_R
  \6\  = JTAG_RST_DBP_RST_CO_N
  \7\  = JTAG_DBP_PMODE
  \8\  = PD_TRST_P3
  \9\  = NC_MIPI60_P9
  \10\  = JTAG_DBP_PREQ_N_R
  \11\  = JTAG_DBP_PRDY_R1_N
  \12\  = P1V8_PCH_AUX
  \13\  = JTAG_TRC_PCH_PTI0_CLK
  \14\  = GND
  \15\  = JTAG_DBP_PCH_DEBUG_CONSENT_N
  \16\  = GND
  \17\  = JTAG_DBP_PRESENT_R_N
  \18\  = NC_DBP_P18
  \19\  = JTAG_TRC_PCH_PTI<0>
  \20\  = NC_DBP_P20
  \21\  = JTAG_TRC_PCH_PTI<1>
  \22\  = NC_DBP_P22
  \23\  = JTAG_TRC_PCH_PTI<2>
  \24\  = NC_DBP_P24
  \25\  = JTAG_TRC_PCH_PTI<3>
  \26\  = NC_DBP_P26
  \27\  = JTAG_TRC_PCH_PTI<4>
  \28\  = NC_DBP_P28
  \29\  = JTAG_TRC_PCH_PTI<5>
  \30\  = NC_DBP_P30
  \31\  = JTAG_TRC_PCH_PTI<6>
  \32\  = NC_DBP_P32
  \33\  = JTAG_TRC_PCH_PTI<7>
  \34\  = NC_DBP_P34
  \35\  = JTAG_TRC_PCH_PTI<8>
  \36\  = JTAG_DBP_BOOT_HALT_N
  \37\  = JTAG_TRC_PCH_PTI<9>
  \38\  = FM_CPU_FBRK_DEBUG_N
  \39\  = JTAG_TRC_PCH_PTI<10>
  \40\  = JTAG_DBP_POWER_BTN_N
  \41\  = JTAG_TRC_PCH_PTI<11>
  \42\  = JTAG_RST_DBP_RSMRST_N
  \43\  = JTAG_TRC_PCH_PTI<12>
  \44\  = NC_DBP_P44
  \45\  = JTAG_TRC_PCH_PTI<13>
  \46\  = NC_DBP_P46
  \47\  = JTAG_TRC_PCH_PTI<14>
  \48\  = SMB_HOST_3V3AUX_XDP_R_SCL
  \49\  = JTAG_TRC_PCH_PTI<15>
  \50\  = SMB_HOST_3V3AUX_XDP_R_SDA
  \51\  = JTAG_DBP_TCK_R_TCK
  \52\  = P3V3_AUX
  \53\  = JTAG_DBP_CPU_HOOK9_MBP3_GTL_N
  \54\  = NC_DBP_P54
  \55\  = JTAG_DBP_CPU_HOOK8_MBP2_GTL_N
  \56\  = NC_DBP_P56
  \57\  = GND
  \58\  = GND
  \59\  = JTAG_TRC_PCH_PTI1_CLK
  \60\  = GND
  G1  = GND
  G2  = GND
  G3  = GND
  G4  = GND

(kicad_pcb
	(version 20260206)
	(generator "pcbnew")
	(generator_version "10.0")
	(general
		(thickness 1.6)
		(legacy_teardrops no)
	)
	(paper "A4")
	(title_block
		(title "03242023_DA0F0TMBIJ0_F0T_Motherboard_J_brd_V01_OCP.brd")
		(comment 1 "Grand Teton / footprint 3716 of 6105 (J42), pads 45-66 of 66")
	)
	(layers
		(0 "F.Cu" signal "TOP")
		(4 "In1.Cu" signal "GND")
		(6 "In2.Cu" signal "IN1")
		(8 "In3.Cu" signal "GND1")
		(10 "In4.Cu" signal "IN2")
		(12 "In5.Cu" signal "GND2")
		(14 "In6.Cu" signal "IN3")
		(16 "In7.Cu" signal "GND3")
		(18 "In8.Cu" signal "VCC")
		(20 "In9.Cu" signal "VCC1")
		(22 "In10.Cu" signal "GND4")
		(24 "In11.Cu" signal "IN4")
		(26 "In12.Cu" signal "GND5")
		(28 "In13.Cu" signal "IN5")
		(30 "In14.Cu" signal "GND6")
		(32 "In15.Cu" signal "IN6")
		(34 "In16.Cu" signal "GND7")
		(2 "B.Cu" signal "BOTTOM")
		(9 "F.Adhes" user "F.Adhesive")
		(11 "B.Adhes" user "B.Adhesive")
		(13 "F.Paste" user "Package Geometry/Pastemask Top")
		(15 "B.Paste" user "Package Geometry/Pastemask Bottom")
		(5 "F.SilkS" user "Ref Des/Silkscreen Top")
		(7 "B.SilkS" user "Ref Des/Silkscreen Bottom")
		(1 "F.Mask" user "Board Geometry/Soldermask Top")
		(3 "B.Mask" user "Board Geometry/Soldermask Bottom")
		(17 "Dwgs.User" user "User.Drawings")
		(19 "Cmts.User" user "User.Comments")
		(21 "Eco1.User" user "User.Eco1")
		(23 "Eco2.User" user "User.Eco2")
		(25 "Edge.Cuts" user "Board Geometry/Outline")
		(27 "Margin" user)
		(31 "F.CrtYd" user "Package Geometry/Place Bound Top")
		(29 "B.CrtYd" user "Package Geometry/Place Bound Bottom")
		(35 "F.Fab" user "Ref Des/Assembly Top")
		(33 "B.Fab" user "Ref Des/Assembly Bottom")
	)
	(footprint ""
		(layer "F.Cu")
		(at 394.899896 -56.999886)
		(property "Reference" "J42"
			(at 4.46278 8.605012 0)
			(unlocked yes)
			(layer "F.SilkS")
			(effects
				(font
					(size 0.7874 0.5842)
					(thickness 0.1524)
				)
				(justify left)
			)
		)
		(property "Value" ""
			(at 0 0 0)
			(layer "F.Fab")
			(effects
				(font
					(size 1.27 1.27)
				)
			)
		)
		(duplicate_pad_numbers_are_jumpers no)
		(pad "43" smd rect
			(at -2.86512 3.24993 270)
			(size 0.2794 2.286)
			(layers "F.Cu" "F.Mask" "F.Paste")
			(net "JTAG_TRC_PCH_PTI<12>")
		)
		(pad "44" smd rect
			(at 2.86512 3.24993 270)
			(size 0.2794 2.286)
			(layers "F.Cu" "F.Mask" "F.Paste")
			(net "NC_DBP_P44")
		)
		(pad "45" smd rect
			(at -2.86512 3.750056 270)
			(size 0.2794 2.286)
			(layers "F.Cu" "F.Mask" "F.Paste")
			(net "JTAG_TRC_PCH_PTI<13>")
		)
		(pad "46" smd rect
			(at 2.86512 3.750056 270)
			(size 0.2794 2.286)
			(layers "F.Cu" "F.Mask" "F.Paste")
			(net "NC_DBP_P46")
		)
		(pad "47" smd rect
			(at -2.86512 4.249928 270)
			(size 0.2794 2.286)
			(layers "F.Cu" "F.Mask" "F.Paste")
			(net "JTAG_TRC_PCH_PTI<14>")
		)
		(pad "48" smd rect
			(at 2.86512 4.249928 270)
			(size 0.2794 2.286)
			(layers "F.Cu" "F.Mask" "F.Paste")
			(net "SMB_HOST_3V3AUX_XDP_R_SCL")
		)
		(pad "49" smd rect
			(at -2.86512 4.750054 270)
			(size 0.2794 2.286)
			(layers "F.Cu" "F.Mask" "F.Paste")
			(net "JTAG_TRC_PCH_PTI<15>")
		)
		(pad "50" smd rect
			(at 2.86512 4.750054 270)
			(size 0.2794 2.286)
			(layers "F.Cu" "F.Mask" "F.Paste")
			(net "SMB_HOST_3V3AUX_XDP_R_SDA")
		)
		(pad "51" smd rect
			(at -2.86512 5.249926 270)
			(size 0.2794 2.286)
			(layers "F.Cu" "F.Mask" "F.Paste")
			(net "JTAG_DBP_TCK_R_TCK")
		)
		(pad "52" smd rect
			(at 2.86512 5.249926 270)
			(size 0.2794 2.286)
			(layers "F.Cu" "F.Mask" "F.Paste")
			(net "P3V3_AUX")
		)
		(pad "53" smd rect
			(at -2.86512 5.750052 270)
			(size 0.2794 2.286)
			(layers "F.Cu" "F.Mask" "F.Paste")
			(net "JTAG_DBP_CPU_HOOK9_MBP3_GTL_N")
		)
		(pad "54" smd rect
			(at 2.86512 5.750052 270)
			(size 0.2794 2.286)
			(layers "F.Cu" "F.Mask" "F.Paste")
			(net "NC_DBP_P54")
		)
		(pad "55" smd rect
			(at -2.86512 6.249924 270)
			(size 0.2794 2.286)
			(layers "F.Cu" "F.Mask" "F.Paste")
			(net "JTAG_DBP_CPU_HOOK8_MBP2_GTL_N")
		)
		(pad "56" smd rect
			(at 2.86512 6.249924 270)
			(size 0.2794 2.286)
			(layers "F.Cu" "F.Mask" "F.Paste")
			(net "NC_DBP_P56")
		)
		(pad "57" smd rect
			(at -2.86512 6.75005 270)
			(size 0.2794 2.286)
			(layers "F.Cu" "F.Mask" "F.Paste")
			(net "GND")
		)
		(pad "58" smd rect
			(at 2.86512 6.75005 270)
			(size 0.2794 2.286)
			(layers "F.Cu" "F.Mask" "F.Paste")
			(net "GND")
		)
		(pad "59" smd rect
			(at -2.86512 7.249922 270)
			(size 0.2794 2.286)
			(layers "F.Cu" "F.Mask" "F.Paste")
			(net "JTAG_TRC_PCH_PTI1_CLK")
		)
		(pad "60" smd rect
			(at 2.86512 7.249922 270)
			(size 0.2794 2.286)
			(layers "F.Cu" "F.Mask" "F.Paste")
			(net "GND")
		)
		(pad "G1" smd rect
			(at 0 -8.065008)
			(size 0.4318 2.54)
			(layers "F.Cu" "F.Mask" "F.Paste")
			(net "GND")
		)
		(pad "G2" smd rect
			(at 0 -3.175)
			(size 0.4318 4.699)
			(layers "F.Cu" "F.Mask" "F.Paste")
			(net "GND")
		)
		(pad "G3" smd rect
			(at 0 3.175)
			(size 0.4318 4.699)
			(layers "F.Cu" "F.Mask" "F.Paste")
			(net "GND")
		)
		(pad "G4" smd rect
			(at 0 8.065008)
			(size 0.4318 2.54)
			(layers "F.Cu" "F.Mask" "F.Paste")
			(net "GND")
		)
	)
)
